(kicad_pcb
	(version 20260206)
	(generator "pcbnew")
	(generator_version "10.0")
	(general
		(thickness 1.6)
		(legacy_teardrops no)
	)
	(paper "A4")
	(title_block
		(title "Bryce Canyon_R.DPB_16317-1_OCP.brd")
		(comment 1 "Bryce Canyon / footprints 296-299 of 2099")
	)
	(layers
		(0 "F.Cu" signal "TOP")
		(4 "In1.Cu" signal "L2GND")
		(6 "In2.Cu" signal "L3")
		(8 "In3.Cu" signal "L4VCC")
		(10 "In4.Cu" signal "L5VCC")
		(12 "In5.Cu" signal "L6")
		(14 "In6.Cu" signal "L7GND")
		(2 "B.Cu" signal "BOTTOM")
		(9 "F.Adhes" user "F.Adhesive")
		(11 "B.Adhes" user "B.Adhesive")
		(13 "F.Paste" user "Package Geometry/Pastemask Top")
		(15 "B.Paste" user "Package Geometry/Pastemask Bottom")
		(5 "F.SilkS" user "Ref Des/Silkscreen Top")
		(7 "B.SilkS" user "Ref Des/Silkscreen Bottom")
		(1 "F.Mask" user "Board Geometry/Soldermask Top")
		(3 "B.Mask" user "Board Geometry/Soldermask Bottom")
		(17 "Dwgs.User" user "User.Drawings")
		(19 "Cmts.User" user "User.Comments")
		(21 "Eco1.User" user "User.Eco1")
		(23 "Eco2.User" user "User.Eco2")
		(25 "Edge.Cuts" user "Board Geometry/Outline")
		(27 "Margin" user)
		(31 "F.CrtYd" user "Package Geometry/Place Bound Top")
		(29 "B.CrtYd" user "Package Geometry/Place Bound Bottom")
		(35 "F.Fab" user "Ref Des/Assembly Top")
		(33 "B.Fab" user "Ref Des/Assembly Bottom")
	)
	(footprint ""
		(layer "F.Cu")
		(at 185.950098 -143.91005 -90)
		(property "Reference" "HDDSAS17"
			(at 0 0 270)
			(layer "F.SilkS")
			(hide yes)
			(effects
				(font
					(size 1.27 1.27)
				)
			)
		)
		(property "Value" "SKT-SAS15P-14P-45-GP"
			(at -20.7645 -8.9789 270)
			(unlocked yes)
			(layer "F.Fab")
			(hide yes)
			(effects
				(font
					(size 1.016 1.016)
					(thickness 0.1524)
				)
			)
		)
		(property "Device Type" "10120818-001C-TRLF"
			(at -20.7645 -10.5029 270)
			(unlocked yes)
			(layer "F.Fab")
			(hide yes)
			(effects
				(font
					(size 1.016 1.016)
					(thickness 0.1524)
				)
			)
		)
		(duplicate_pad_numbers_are_jumpers no)
		(fp_line
			(start 1.651 4.2926)
			(end 1.651 3.0099)
			(stroke
				(width 0.1524)
				(type default)
			)
			(layer "F.SilkS")
		)
		(fp_line
			(start 8.509 4.2926)
			(end 1.651 4.2926)
			(stroke
				(width 0.1524)
				(type default)
			)
			(layer "F.SilkS")
		)
		(fp_line
			(start -23.4188 3.0099)
			(end -23.4188 -3.2512)
			(stroke
				(width 0.1524)
				(type default)
			)
			(layer "F.SilkS")
		)
		(fp_line
			(start 1.651 3.0099)
			(end -23.4188 3.0099)
			(stroke
				(width 0.1524)
				(type default)
			)
			(layer "F.SilkS")
		)
		(fp_line
			(start 8.509 3.0099)
			(end 8.509 4.2926)
			(stroke
				(width 0.1524)
				(type default)
			)
			(layer "F.SilkS")
		)
		(fp_line
			(start 23.4188 3.0099)
			(end 8.509 3.0099)
			(stroke
				(width 0.1524)
				(type default)
			)
			(layer "F.SilkS")
		)
		(fp_line
			(start -23.4188 -3.2512)
			(end 23.4188 -3.2512)
			(stroke
				(width 0.1524)
				(type default)
			)
			(layer "F.SilkS")
		)
		(fp_line
			(start 23.4188 -3.2512)
			(end 23.4188 3.0099)
			(stroke
				(width 0.1524)
				(type default)
			)
			(layer "F.SilkS")
		)
		(fp_line
			(start 15.5067 -3.3401)
			(end 16.2687 -3.3401)
			(stroke
				(width 0.3302)
				(type default)
			)
			(layer "F.SilkS")
		)
		(fp_poly
			(pts
				(xy 15.868904 -3.230372) (xy 16.503904 -3.865372) (xy 15.233904 -3.865372)
			)
			(stroke
				(width 0)
				(type default)
			)
			(fill yes)
			(layer "F.SilkS")
		)
		(fp_poly
			(pts
				(xy -22.8727 -2.7559) (xy 22.8727 -2.7559) (xy 22.8727 2.7559) (xy 8.255 2.7559) (xy 8.255 3.5179)
				(xy 1.905 3.5179) (xy 1.905 2.7559) (xy -22.8727 2.7559)
			)
			(stroke
				(width 0)
				(type default)
			)
			(fill no)
			(layer "F.CrtYd")
		)
		(fp_poly
			(pts
				(xy 1.397 4.5466) (xy 1.397 3.2639) (xy -23.6728 3.2639) (xy -23.6728 -3.5052) (xy 23.6728 -3.5052)
				(xy 23.6728 -0.00635) (xy 22.8727 -0.00635) (xy 22.8727 -2.7559) (xy -22.8727 -2.7559) (xy -22.8727 2.7559)
				(xy 1.905 2.7559) (xy 1.905 3.5179) (xy 8.255 3.5179) (xy 8.255 2.7559) (xy 22.8727 2.7559) (xy 22.8727 0.00635)
				(xy 23.6728 0.00635) (xy 23.6728 3.2639) (xy 8.763 3.2639) (xy 8.763 4.5466)
			)
			(stroke
				(width 0)
				(type default)
			)
			(fill no)
			(layer "F.CrtYd")
		)
		(fp_poly
			(pts
				(xy 1.397 4.5466) (xy 1.397 3.2639) (xy -23.6728 3.2639) (xy -23.6728 -3.5052) (xy 23.6728 -3.5052)
				(xy 23.6728 3.2639) (xy 8.763 3.2639) (xy 8.763 4.5466)
			)
			(stroke
				(width 0)
				(type default)
			)
			(fill no)
			(layer "F.Fab")
		)
		(pad "" np_thru_hole circle
			(at -18.874994 0 270)
			(size 0.254 0.254)
			(drill 1.3462)
			(layers "*.Cu" "*.Mask")
			(clearance 0.9017)
			(thermal_gap 0.9017)
		)
		(pad "" np_thru_hole circle
			(at 18.874994 0 270)
			(size 0.254 0.254)
			(drill 0.9398)
			(layers "*.Cu" "*.Mask")
			(clearance 0.6985)
			(thermal_gap 0.6985)
		)
		(pad "G1" smd rect
			(at 21.874988 0 270)
			(size 2.5908 2.5908)
			(layers "F.Cu" "F.Mask" "F.Paste")
			(net "GND")
		)
		(pad "G2" smd rect
			(at -21.874988 0 270)
			(size 2.5908 2.5908)
			(layers "F.Cu" "F.Mask" "F.Paste")
			(net "GND")
		)
		(pad "P1" smd rect
			(at 1.905 -1.82499 270)
			(size 0.6096 2.3622)
			(layers "F.Cu" "F.Mask" "F.Paste")
			(net "Net_1719")
		)
		(pad "P2" smd rect
			(at 0.635 -1.82499 270)
			(size 0.6096 2.3622)
			(layers "F.Cu" "F.Mask" "F.Paste")
			(net "Net_1720")
		)
		(pad "P3" smd rect
			(at -0.635 -1.82499 270)
			(size 0.6096 2.3622)
			(layers "F.Cu" "F.Mask" "F.Paste")
			(net "Net_1721")
		)
		(pad "P4" smd rect
			(at -1.905 -1.82499 270)
			(size 0.6096 2.3622)
			(layers "F.Cu" "F.Mask" "F.Paste")
			(net "GND")
		)
		(pad "P5" smd rect
			(at -3.175 -1.82499 270)
			(size 0.6096 2.3622)
			(layers "F.Cu" "F.Mask" "F.Paste")
			(net "HDD_PRSNT_17")
		)
		(pad "P6" smd rect
			(at -4.445 -1.82499 270)
			(size 0.6096 2.3622)
			(layers "F.Cu" "F.Mask" "F.Paste")
			(net "GND")
		)
		(pad "P7" smd rect
			(at -5.715 -1.82499 270)
			(size 0.6096 2.3622)
			(layers "F.Cu" "F.Mask" "F.Paste")
			(net "5V_PRE_17")
		)
		(pad "P8" smd rect
			(at -6.985 -1.82499 270)
			(size 0.6096 2.3622)
			(layers "F.Cu" "F.Mask" "F.Paste")
			(net "P5V_HDD17")
		)
		(pad "P9" smd rect
			(at -8.255 -1.82499 270)
			(size 0.6096 2.3622)
			(layers "F.Cu" "F.Mask" "F.Paste")
			(net "P5V_HDD17")
		)
		(pad "P10" smd rect
			(at -9.525 -1.82499 270)
			(size 0.6096 2.3622)
			(layers "F.Cu" "F.Mask" "F.Paste")
			(net "GND")
		)
		(pad "P11" smd rect
			(at -10.795 -1.82499 270)
			(size 0.6096 2.3622)
			(layers "F.Cu" "F.Mask" "F.Paste")
			(net "ACT_HDD_17")
		)
		(pad "P12" smd rect
			(at -12.065 -1.82499 270)
			(size 0.6096 2.3622)
			(layers "F.Cu" "F.Mask" "F.Paste")
			(net "GND")
		)
		(pad "P13" smd rect
			(at -13.335 -1.82499 270)
			(size 0.6096 2.3622)
			(layers "F.Cu" "F.Mask" "F.Paste")
			(net "12V_PRE_17")
		)
		(pad "P14" smd rect
			(at -14.605 -1.82499 270)
			(size 0.6096 2.3622)
			(layers "F.Cu" "F.Mask" "F.Paste")
			(net "P12V_HDD17")
		)
		(pad "P15" smd rect
			(at -15.875 -1.82499 270)
			(size 0.6096 2.3622)
			(layers "F.Cu" "F.Mask" "F.Paste")
			(net "P12V_HDD17")
		)
		(pad "S1" smd rect
			(at 15.875 -1.82499 270)
			(size 0.6096 2.3622)
			(layers "F.Cu" "F.Mask" "F.Paste")
			(net "GND")
		)
		(pad "S2" smd rect
			(at 14.605 -1.82499 270)
			(size 0.6096 2.3622)
			(layers "F.Cu" "F.Mask" "F.Paste")
			(net "SAS_HDD_RX_P17")
		)
		(pad "S3" smd rect
			(at 13.335 -1.82499 270)
			(size 0.6096 2.3622)
			(layers "F.Cu" "F.Mask" "F.Paste")
			(net "SAS_HDD_RX_N17")
		)
		(pad "S4" smd rect
			(at 12.065 -1.82499 270)
			(size 0.6096 2.3622)
			(layers "F.Cu" "F.Mask" "F.Paste")
			(net "GND")
		)
		(pad "S5" smd rect
			(at 10.795 -1.82499 270)
			(size 0.6096 2.3622)
			(layers "F.Cu" "F.Mask" "F.Paste")
			(net "PHY_DRV_B_TO_SCC_B_17_DN")
		)
		(pad "S6" smd rect
			(at 9.525 -1.82499 270)
			(size 0.6096 2.3622)
			(layers "F.Cu" "F.Mask" "F.Paste")
			(net "PHY_DRV_B_TO_SCC_B_17_DP")
		)
		(pad "S7" smd rect
			(at 8.255 -1.82499 270)
			(size 0.6096 2.3622)
			(layers "F.Cu" "F.Mask" "F.Paste")
			(net "GND")
		)
		(pad "S8" smd rect
			(at 7.480046 2.845054 270)
			(size 0.508 2.3622)
			(layers "F.Cu" "F.Mask" "F.Paste")
			(net "GND")
		)
		(pad "S9" smd rect
			(at 6.679946 2.845054 270)
			(size 0.508 2.3622)
			(layers "F.Cu" "F.Mask" "F.Paste")
			(net "Net_440")
		)
		(pad "S10" smd rect
			(at 5.8801 2.845054 270)
			(size 0.508 2.3622)
			(layers "F.Cu" "F.Mask" "F.Paste")
			(net "Net_332")
		)
		(pad "S11" smd rect
			(at 5.08 2.845054 270)
			(size 0.508 2.3622)
			(layers "F.Cu" "F.Mask" "F.Paste")
			(net "GND")
		)
		(pad "S12" smd rect
			(at 4.2799 2.845054 270)
			(size 0.508 2.3622)
			(layers "F.Cu" "F.Mask" "F.Paste")
			(net "Net_368")
		)
		(pad "S13" smd rect
			(at 3.480054 2.845054 270)
			(size 0.508 2.3622)
			(layers "F.Cu" "F.Mask" "F.Paste")
			(net "Net_404")
		)
		(pad "S14" smd rect
			(at 2.679954 2.845054 270)
			(size 0.508 2.3622)
			(layers "F.Cu" "F.Mask" "F.Paste")
			(net "GND")
		)
		(zone
			(layer "F.Cu")
			(hatch none 0.5)
			(connect_pads
				(clearance 0)
			)
			(min_thickness 0.25)
			(keepout
				(tracks not_allowed)
				(vias allowed)
				(pads allowed)
				(copperpour not_allowed)
				(footprints allowed)
			)
			(placement
				(enabled no)
				(sheetname "")
			)
			(fill
				(thermal_gap 0.5)
				(thermal_bridge_width 0.5)
				(island_removal_mode 0)
			)
			(polygon
				(pts
					(xy 189.607698 -160.64865) (xy 182.533798 -160.64865) (xy 182.533798 -167.58285) (xy 183.638698 -167.58285)
					(xy 183.638698 -163.46805) (xy 188.261498 -163.46805) (xy 188.261498 -167.58285) (xy 189.607698 -167.58285)
				)
			)
		)
		(zone
			(layer "F.Cu")
			(hatch none 0.5)
			(connect_pads
				(clearance 0)
			)
			(min_thickness 0.25)
			(keepout
				(tracks allowed)
				(vias not_allowed)
				(pads allowed)
				(copperpour not_allowed)
				(footprints allowed)
			)
			(placement
				(enabled no)
				(sheetname "")
			)
			(fill
				(thermal_gap 0.5)
				(thermal_bridge_width 0.5)
				(island_removal_mode 0)
			)
			(polygon
				(pts
					(xy 189.607698 -160.64865) (xy 182.533798 -160.64865) (xy 182.533798 -167.58285) (xy 183.638698 -167.58285)
					(xy 183.638698 -163.46805) (xy 188.261498 -163.46805) (xy 188.261498 -167.58285) (xy 189.607698 -167.58285)
				)
			)
		)
		(zone
			(layer "F.Cu")
			(hatch none 0.5)
			(connect_pads
				(clearance 0)
			)
			(min_thickness 0.25)
			(keepout
				(tracks allowed)
				(vias not_allowed)
				(pads allowed)
				(copperpour not_allowed)
				(footprints allowed)
			)
			(placement
				(enabled no)
				(sheetname "")
			)
			(fill
				(thermal_gap 0.5)
				(thermal_bridge_width 0.5)
				(island_removal_mode 0)
			)
			(polygon
				(pts
					(xy 189.607698 -127.17145) (xy 182.533798 -127.17145) (xy 182.533798 -120.23725) (xy 183.638698 -120.23725)
					(xy 183.638698 -124.35205) (xy 188.261498 -124.35205) (xy 188.261498 -120.23725) (xy 189.607698 -120.23725)
				)
			)
		)
		(zone
			(layer "F.Cu")
			(hatch none 0.5)
			(connect_pads
				(clearance 0)
			)
			(min_thickness 0.25)
			(keepout
				(tracks not_allowed)
				(vias allowed)
				(pads allowed)
				(copperpour not_allowed)
				(footprints allowed)
			)
			(placement
				(enabled no)
				(sheetname "")
			)
			(fill
				(thermal_gap 0.5)
				(thermal_bridge_width 0.5)
				(island_removal_mode 0)
			)
			(polygon
				(pts
					(xy 189.607698 -127.17145) (xy 182.533798 -127.17145) (xy 182.533798 -120.23725) (xy 183.638698 -120.23725)
					(xy 183.638698 -124.35205) (xy 188.261498 -124.35205) (xy 188.261498 -120.23725) (xy 189.607698 -120.23725)
				)
			)
		)
		(zone
			(layers "F.Cu" "B.Cu" "In1.Cu" "In2.Cu" "In3.Cu" "In4.Cu" "In5.Cu" "In6.Cu")
			(hatch none 0.5)
			(connect_pads
				(clearance 0)
			)
			(min_thickness 0.25)
			(keepout
				(tracks not_allowed)
				(vias allowed)
				(pads allowed)
				(copperpour not_allowed)
				(footprints allowed)
			)
			(placement
				(enabled no)
				(sheetname "")
			)
			(fill
				(thermal_gap 0.5)
				(thermal_bridge_width 0.5)
				(island_removal_mode 0)
			)
			(polygon
				(pts
					(arc
						(start 186.724798 -125.035056)
						(mid 185.175398 -125.035056)
						(end 186.724798 -125.035056)
					)
				)
			)
		)
		(zone
			(layers "F.Cu" "B.Cu" "In1.Cu" "In2.Cu" "In3.Cu" "In4.Cu" "In5.Cu" "In6.Cu")
			(hatch none 0.5)
			(connect_pads
				(clearance 0)
			)
			(min_thickness 0.25)
			(keepout
				(tracks not_allowed)
				(vias allowed)
				(pads allowed)
				(copperpour not_allowed)
				(footprints allowed)
			)
			(placement
				(enabled no)
				(sheetname "")
			)
			(fill
				(thermal_gap 0.5)
				(thermal_bridge_width 0.5)
				(island_removal_mode 0)
			)
			(polygon
				(pts
					(arc
						(start 186.927998 -162.785044)
						(mid 184.972198 -162.785044)
						(end 186.927998 -162.785044)
					)
				)
			)
		)
	)
	(footprint ""
		(layer "F.Cu")
		(at 398.145 -13.335 180)
		(property "Reference" "R823"
			(at 0 0 180)
			(layer "F.SilkS")
			(hide yes)
			(effects
				(font
					(size 1.27 1.27)
				)
			)
		)
		(property "Value" "0R2J-2-GP"
			(at 0.064008 -3.993896 180)
			(unlocked yes)
			(layer "F.Fab")
			(hide yes)
			(effects
				(font
					(size 1.016 1.016)
					(thickness 0.1524)
				)
			)
		)
		(property "Device Type" "R402H16"
			(at 0.064008 -5.517896 180)
			(unlocked yes)
			(layer "F.Fab")
			(hide yes)
			(effects
				(font
					(size 1.016 1.016)
					(thickness 0.1524)
				)
			)
		)
		(duplicate_pad_numbers_are_jumpers no)
		(fp_line
			(start 0.508 -0.9398)
			(end -0.508 -0.9398)
			(stroke
				(width 0.1524)
				(type default)
			)
			(layer "F.SilkS")
		)
		(fp_line
			(start -0.508 -0.9398)
			(end -0.508 0.9398)
			(stroke
				(width 0.1524)
				(type default)
			)
			(layer "F.SilkS")
		)
		(fp_rect
			(start -0.508 0.9398)
			(end 0.508 -0.9398)
			(stroke
				(width 0)
				(type default)
			)
			(fill no)
			(layer "F.CrtYd")
		)
		(fp_rect
			(start -0.508 0.9398)
			(end 0.508 -0.9398)
			(stroke
				(width 0)
				(type default)
			)
			(fill no)
			(layer "F.Fab")
		)
		(pad "1" smd custom
			(at 0 -0.4445 180)
			(size 0.1397 0.1397)
			(layers "F.Cu" "F.Mask" "F.Paste")
			(net "SW_HDD_G32")
			(options
				(clearance outline)
				(anchor circle)
			)
			(primitives
				(gr_poly
					(pts
						(arc
							(start -0.1778 -0.2794)
							(mid -0.249642 -0.249642)
							(end -0.2794 -0.1778)
						)
						(arc
							(start -0.2794 0.1778)
							(mid -0.249642 0.249642)
							(end -0.1778 0.2794)
						)
						(arc
							(start 0.1778 0.2794)
							(mid 0.249642 0.249642)
							(end 0.2794 0.1778)
						)
						(arc
							(start 0.2794 -0.1778)
							(mid 0.249642 -0.249642)
							(end 0.1778 -0.2794)
						)
					)
					(width 0)
					(fill yes)
				)
			)
		)
		(pad "2" smd custom
			(at 0 0.4445 180)
			(size 0.1397 0.1397)
			(layers "F.Cu" "F.Mask" "F.Paste")
			(net "SW_HDD_R32")
			(options
				(clearance outline)
				(anchor circle)
			)
			(primitives
				(gr_poly
					(pts
						(arc
							(start -0.1778 -0.2794)
							(mid -0.249642 -0.249642)
							(end -0.2794 -0.1778)
						)
						(arc
							(start -0.2794 0.1778)
							(mid -0.249642 0.249642)
							(end -0.1778 0.2794)
						)
						(arc
							(start 0.1778 0.2794)
							(mid 0.249642 0.249642)
							(end 0.2794 0.1778)
						)
						(arc
							(start 0.2794 -0.1778)
							(mid 0.249642 -0.249642)
							(end 0.1778 -0.2794)
						)
					)
					(width 0)
					(fill yes)
				)
			)
		)
	)
	(footprint ""
		(layer "F.Cu")
		(at 459.8162 -155.575 -90)
		(property "Reference" "R577"
			(at 0 0 270)
			(layer "F.SilkS")
			(hide yes)
			(effects
				(font
					(size 1.27 1.27)
				)
			)
		)
		(property "Value" "2R6F-GP"
			(at -0.0508 -4.8514 270)
			(unlocked yes)
			(layer "F.Fab")
			(hide yes)
			(effects
				(font
					(size 1.016 1.016)
					(thickness 0.1524)
				)
			)
		)
		(property "Device Type" "R1206H26"
			(at 0 -6.3754 270)
			(unlocked yes)
			(layer "F.Fab")
			(hide yes)
			(effects
				(font
					(size 1.016 1.016)
					(thickness 0.1524)
				)
			)
		)
		(duplicate_pad_numbers_are_jumpers no)
		(fp_line
			(start -1.016 2.2352)
			(end -1.016 -2.2352)
			(stroke
				(width 0.1524)
				(type default)
			)
			(layer "F.SilkS")
		)
		(fp_line
			(start 1.016 2.2352)
			(end -1.016 2.2352)
			(stroke
				(width 0.1524)
				(type default)
			)
			(layer "F.SilkS")
		)
		(fp_line
			(start -1.016 -2.2352)
			(end 1.016 -2.2352)
			(stroke
				(width 0.1524)
				(type default)
			)
			(layer "F.SilkS")
		)
		(fp_line
			(start 1.016 -2.2352)
			(end 1.016 2.2352)
			(stroke
				(width 0.1524)
				(type default)
			)
			(layer "F.SilkS")
		)
		(fp_rect
			(start -1.0922 2.3114)
			(end 1.0922 -2.3114)
			(stroke
				(width 0)
				(type default)
			)
			(fill no)
			(layer "F.CrtYd")
		)
		(fp_poly
			(pts
				(xy -1.0922 -2.3114) (xy 1.0922 -2.3114) (xy 1.0922 2.3114) (xy -1.0922 2.3114)
			)
			(stroke
				(width 0)
				(type default)
			)
			(fill no)
			(layer "F.Fab")
		)
		(pad "1" smd rect
			(at 0 -1.397 270)
			(size 1.651 1.27)
			(layers "F.Cu" "F.Mask" "F.Paste")
			(net "P12V_HDD22")
		)
		(pad "2" smd rect
			(at 0 1.397 270)
			(size 1.651 1.27)
			(layers "F.Cu" "F.Mask" "F.Paste")
			(net "12V_PRE_22")
		)
	)
	(footprint ""
		(layer "F.Cu")
		(at 15.24 -133.096 180)
		(property "Reference" "R362"
			(at 0 0 180)
			(layer "F.SilkS")
			(hide yes)
			(effects
				(font
					(size 1.27 1.27)
				)
			)
		)
		(property "Value" "200KR2F-L-GP"
			(at 0.064008 -3.993896 180)
			(unlocked yes)
			(layer "F.Fab")
			(hide yes)
			(effects
				(font
					(size 1.016 1.016)
					(thickness 0.1524)
				)
			)
		)
		(property "Device Type" "R402H16"
			(at 0.064008 -5.517896 180)
			(unlocked yes)
			(layer "F.Fab")
			(hide yes)
			(effects
				(font
					(size 1.016 1.016)
					(thickness 0.1524)
				)
			)
		)
		(duplicate_pad_numbers_are_jumpers no)
		(fp_line
			(start 0.508 -0.9398)
			(end -0.508 -0.9398)
			(stroke
				(width 0.1524)
				(type default)
			)
			(layer "F.SilkS")
		)
		(fp_line
			(start -0.508 -0.9398)
			(end -0.508 0.9398)
			(stroke
				(width 0.1524)
				(type default)
			)
			(layer "F.SilkS")
		)
		(fp_rect
			(start -0.508 0.9398)
			(end 0.508 -0.9398)
			(stroke
				(width 0)
				(type default)
			)
			(fill no)
			(layer "F.CrtYd")
		)
		(fp_rect
			(start -0.508 0.9398)
			(end 0.508 -0.9398)
			(stroke
				(width 0)
				(type default)
			)
			(fill no)
			(layer "F.Fab")
		)
		(pad "1" smd custom
			(at 0 -0.4445 180)
			(size 0.1397 0.1397)
			(layers "F.Cu" "F.Mask" "F.Paste")
			(net "SW_HDD_R12")
			(options
				(clearance outline)
				(anchor circle)
			)
			(primitives
				(gr_poly
					(pts
						(arc
							(start -0.1778 -0.2794)
							(mid -0.249642 -0.249642)
							(end -0.2794 -0.1778)
						)
						(arc
							(start -0.2794 0.1778)
							(mid -0.249642 0.249642)
							(end -0.1778 0.2794)
						)
						(arc
							(start 0.1778 0.2794)
							(mid 0.249642 0.249642)
							(end 0.2794 0.1778)
						)
						(arc
							(start 0.2794 -0.1778)
							(mid 0.249642 -0.249642)
							(end 0.1778 -0.2794)
						)
					)
					(width 0)
					(fill yes)
				)
			)
		)
		(pad "2" smd custom
			(at 0 0.4445 180)
			(size 0.1397 0.1397)
			(layers "F.Cu" "F.Mask" "F.Paste")
			(net "SW_HDD_N12")
			(options
				(clearance outline)
				(anchor circle)
			)
			(primitives
				(gr_poly
					(pts
						(arc
							(start -0.1778 -0.2794)
							(mid -0.249642 -0.249642)
							(end -0.2794 -0.1778)
						)
						(arc
							(start -0.2794 0.1778)
							(mid -0.249642 0.249642)
							(end -0.1778 0.2794)
						)
						(arc
							(start 0.1778 0.2794)
							(mid 0.249642 0.249642)
							(end 0.2794 0.1778)
						)
						(arc
							(start 0.2794 -0.1778)
							(mid 0.249642 -0.249642)
							(end 0.1778 -0.2794)
						)
					)
					(width 0)
					(fill yes)
				)
			)
		)
	)
)
